(kicad_pcb
	(version 20260206)
	(generator "pcbnew")
	(generator_version "10.0")
	(general
		(thickness 1.6)
		(legacy_teardrops no)
	)
	(paper "A4")
	(title_block
		(title "Wiwynn_Tioga_Pass_MB.brd")
		(comment 1 "Tioga Pass / footprint 2717 of 4770 (J9L1), pads 1-123 of 291")
	)
	(layers
		(0 "F.Cu" signal "TOP")
		(4 "In1.Cu" signal "L2GND")
		(6 "In2.Cu" signal "L3")
		(8 "In3.Cu" signal "L4GND")
		(10 "In4.Cu" signal "L5")
		(12 "In5.Cu" signal "L6GND")
		(14 "In6.Cu" signal "L7VCC")
		(16 "In7.Cu" signal "L8VCC")
		(18 "In8.Cu" signal "L9GND")
		(20 "In9.Cu" signal "L10")
		(22 "In10.Cu" signal "L11GND")
		(24 "In11.Cu" signal "L12")
		(26 "In12.Cu" signal "L13GND")
		(2 "B.Cu" signal "BOTTOM")
		(9 "F.Adhes" user "F.Adhesive")
		(11 "B.Adhes" user "B.Adhesive")
		(13 "F.Paste" user "Package Geometry/Pastemask Top")
		(15 "B.Paste" user "Package Geometry/Pastemask Bottom")
		(5 "F.SilkS" user "Ref Des/Silkscreen Top")
		(7 "B.SilkS" user "Ref Des/Silkscreen Bottom")
		(1 "F.Mask" user "Board Geometry/Soldermask Top")
		(3 "B.Mask" user "Board Geometry/Soldermask Bottom")
		(17 "Dwgs.User" user "User.Drawings")
		(19 "Cmts.User" user "User.Comments")
		(21 "Eco1.User" user "User.Eco1")
		(23 "Eco2.User" user "User.Eco2")
		(25 "Edge.Cuts" user "Board Geometry/Outline")
		(27 "Margin" user)
		(31 "F.CrtYd" user "Package Geometry/Place Bound Top")
		(29 "B.CrtYd" user "Package Geometry/Place Bound Bottom")
		(35 "F.Fab" user "Ref Des/Assembly Top")
		(33 "B.Fab" user "Ref Des/Assembly Bottom")
	)
	(footprint ""
		(layer "B.Cu")
		(at 29.699458 -152.078436 90)
		(property "Reference" "J9L1"
			(at 2.200148 37.737542 0)
			(unlocked yes)
			(layer "B.SilkS")
			(effects
				(font
					(size 0.7874 0.5842)
					(thickness 0.1524)
				)
				(justify left mirror)
			)
		)
		(property "Value" ""
			(at 0 0 90)
			(layer "B.Fab")
			(effects
				(font
					(size 1.27 1.27)
				)
				(justify mirror)
			)
		)
		(duplicate_pad_numbers_are_jumpers no)
		(pad "" thru_hole circle
			(at -2.29997 -5.649976 270)
			(size 2.8194 2.8194)
			(drill 2.4384)
			(layers "*.Cu" "*.Mask")
			(remove_unused_layers no)
			(clearance 0.127)
			(thermal_gap 0.127)
		)
		(pad "" thru_hole oval
			(at -2.29997 68.90004 270)
			(size 2.8194 1.5748)
			(drill oval 2.4384 1.1938)
			(layers "*.Cu" "*.Mask")
			(remove_unused_layers no)
			(clearance 0.127)
			(thermal_gap 0.127)
		)
		(pad "" thru_hole circle
			(at -2.29997 132.299964 270)
			(size 2.8194 2.8194)
			(drill 2.4384)
			(layers "*.Cu" "*.Mask")
			(remove_unused_layers no)
			(clearance 0.127)
			(thermal_gap 0.127)
		)
		(pad "1" smd rect
			(at 0 0 270)
			(size 1.8034 0.508)
			(layers "B.Cu" "B.Mask" "B.Paste")
			(net "P12V_NVDIMM_KLM")
		)
		(pad "2" smd rect
			(at 0 0.849884 270)
			(size 1.8034 0.508)
			(layers "B.Cu" "B.Mask" "B.Paste")
			(net "GND")
		)
		(pad "3" smd rect
			(at 0 1.700022 270)
			(size 1.8034 0.508)
			(layers "B.Cu" "B.Mask" "B.Paste")
			(net "M_M_DQ<4>")
		)
		(pad "4" smd rect
			(at 0 2.549906 270)
			(size 1.8034 0.508)
			(layers "B.Cu" "B.Mask" "B.Paste")
			(net "GND")
		)
		(pad "5" smd rect
			(at 0 3.400044 270)
			(size 1.8034 0.508)
			(layers "B.Cu" "B.Mask" "B.Paste")
			(net "M_M_DQ<0>")
		)
		(pad "6" smd rect
			(at 0 4.249928 270)
			(size 1.8034 0.508)
			(layers "B.Cu" "B.Mask" "B.Paste")
			(net "GND")
		)
		(pad "7" smd rect
			(at 0 5.100066 270)
			(size 1.8034 0.508)
			(layers "B.Cu" "B.Mask" "B.Paste")
			(net "M_M_DQS_DP<9>")
		)
		(pad "8" smd rect
			(at 0 5.94995 270)
			(size 1.8034 0.508)
			(layers "B.Cu" "B.Mask" "B.Paste")
			(net "M_M_DQS_DN<9>")
		)
		(pad "9" smd rect
			(at 0 6.800088 270)
			(size 1.8034 0.508)
			(layers "B.Cu" "B.Mask" "B.Paste")
			(net "GND")
		)
		(pad "10" smd rect
			(at 0 7.649972 270)
			(size 1.8034 0.508)
			(layers "B.Cu" "B.Mask" "B.Paste")
			(net "M_M_DQ<6>")
		)
		(pad "11" smd rect
			(at 0 8.50011 270)
			(size 1.8034 0.508)
			(layers "B.Cu" "B.Mask" "B.Paste")
			(net "GND")
		)
		(pad "12" smd rect
			(at 0 9.349994 270)
			(size 1.8034 0.508)
			(layers "B.Cu" "B.Mask" "B.Paste")
			(net "M_M_DQ<2>")
		)
		(pad "13" smd rect
			(at 0 10.199878 270)
			(size 1.8034 0.508)
			(layers "B.Cu" "B.Mask" "B.Paste")
			(net "GND")
		)
		(pad "14" smd rect
			(at 0 11.050016 270)
			(size 1.8034 0.508)
			(layers "B.Cu" "B.Mask" "B.Paste")
			(net "M_M_DQ<12>")
		)
		(pad "15" smd rect
			(at 0 11.8999 270)
			(size 1.8034 0.508)
			(layers "B.Cu" "B.Mask" "B.Paste")
			(net "GND")
		)
		(pad "16" smd rect
			(at 0 12.750038 270)
			(size 1.8034 0.508)
			(layers "B.Cu" "B.Mask" "B.Paste")
			(net "M_M_DQ<8>")
		)
		(pad "17" smd rect
			(at 0 13.599922 270)
			(size 1.8034 0.508)
			(layers "B.Cu" "B.Mask" "B.Paste")
			(net "GND")
		)
		(pad "18" smd rect
			(at 0 14.45006 270)
			(size 1.8034 0.508)
			(layers "B.Cu" "B.Mask" "B.Paste")
			(net "M_M_DQS_DP<10>")
		)
		(pad "19" smd rect
			(at 0 15.299944 270)
			(size 1.8034 0.508)
			(layers "B.Cu" "B.Mask" "B.Paste")
			(net "M_M_DQS_DN<10>")
		)
		(pad "20" smd rect
			(at 0 16.150082 270)
			(size 1.8034 0.508)
			(layers "B.Cu" "B.Mask" "B.Paste")
			(net "GND")
		)
		(pad "21" smd rect
			(at 0 16.999966 270)
			(size 1.8034 0.508)
			(layers "B.Cu" "B.Mask" "B.Paste")
			(net "M_M_DQ<14>")
		)
		(pad "22" smd rect
			(at 0 17.850104 270)
			(size 1.8034 0.508)
			(layers "B.Cu" "B.Mask" "B.Paste")
			(net "GND")
		)
		(pad "23" smd rect
			(at 0 18.699988 270)
			(size 1.8034 0.508)
			(layers "B.Cu" "B.Mask" "B.Paste")
			(net "M_M_DQ<10>")
		)
		(pad "24" smd rect
			(at 0 19.550126 270)
			(size 1.8034 0.508)
			(layers "B.Cu" "B.Mask" "B.Paste")
			(net "GND")
		)
		(pad "25" smd rect
			(at 0 20.40001 270)
			(size 1.8034 0.508)
			(layers "B.Cu" "B.Mask" "B.Paste")
			(net "M_M_DQ<20>")
		)
		(pad "26" smd rect
			(at 0 21.249894 270)
			(size 1.8034 0.508)
			(layers "B.Cu" "B.Mask" "B.Paste")
			(net "GND")
		)
		(pad "27" smd rect
			(at 0 22.100032 270)
			(size 1.8034 0.508)
			(layers "B.Cu" "B.Mask" "B.Paste")
			(net "M_M_DQ<16>")
		)
		(pad "28" smd rect
			(at 0 22.949916 270)
			(size 1.8034 0.508)
			(layers "B.Cu" "B.Mask" "B.Paste")
			(net "GND")
		)
		(pad "29" smd rect
			(at 0 23.800054 270)
			(size 1.8034 0.508)
			(layers "B.Cu" "B.Mask" "B.Paste")
			(net "M_M_DQS_DP<11>")
		)
		(pad "30" smd rect
			(at 0 24.649938 270)
			(size 1.8034 0.508)
			(layers "B.Cu" "B.Mask" "B.Paste")
			(net "M_M_DQS_DN<11>")
		)
		(pad "31" smd rect
			(at 0 25.500076 270)
			(size 1.8034 0.508)
			(layers "B.Cu" "B.Mask" "B.Paste")
			(net "GND")
		)
		(pad "32" smd rect
			(at 0 26.34996 270)
			(size 1.8034 0.508)
			(layers "B.Cu" "B.Mask" "B.Paste")
			(net "M_M_DQ<22>")
		)
		(pad "33" smd rect
			(at 0 27.200098 270)
			(size 1.8034 0.508)
			(layers "B.Cu" "B.Mask" "B.Paste")
			(net "GND")
		)
		(pad "34" smd rect
			(at 0 28.049982 270)
			(size 1.8034 0.508)
			(layers "B.Cu" "B.Mask" "B.Paste")
			(net "M_M_DQ<18>")
		)
		(pad "35" smd rect
			(at 0 28.90012 270)
			(size 1.8034 0.508)
			(layers "B.Cu" "B.Mask" "B.Paste")
			(net "GND")
		)
		(pad "36" smd rect
			(at 0 29.750004 270)
			(size 1.8034 0.508)
			(layers "B.Cu" "B.Mask" "B.Paste")
			(net "M_M_DQ<28>")
		)
		(pad "37" smd rect
			(at 0 30.599888 270)
			(size 1.8034 0.508)
			(layers "B.Cu" "B.Mask" "B.Paste")
			(net "GND")
		)
		(pad "38" smd rect
			(at 0 31.450026 270)
			(size 1.8034 0.508)
			(layers "B.Cu" "B.Mask" "B.Paste")
			(net "M_M_DQ<24>")
		)
		(pad "39" smd rect
			(at 0 32.29991 270)
			(size 1.8034 0.508)
			(layers "B.Cu" "B.Mask" "B.Paste")
			(net "GND")
		)
		(pad "40" smd rect
			(at 0 33.150048 270)
			(size 1.8034 0.508)
			(layers "B.Cu" "B.Mask" "B.Paste")
			(net "M_M_DQS_DP<12>")
		)
		(pad "41" smd rect
			(at 0 33.999932 270)
			(size 1.8034 0.508)
			(layers "B.Cu" "B.Mask" "B.Paste")
			(net "M_M_DQS_DN<12>")
		)
		(pad "42" smd rect
			(at 0 34.85007 270)
			(size 1.8034 0.508)
			(layers "B.Cu" "B.Mask" "B.Paste")
			(net "GND")
		)
		(pad "43" smd rect
			(at 0 35.699954 270)
			(size 1.8034 0.508)
			(layers "B.Cu" "B.Mask" "B.Paste")
			(net "M_M_DQ<30>")
		)
		(pad "44" smd rect
			(at 0 36.550092 270)
			(size 1.8034 0.508)
			(layers "B.Cu" "B.Mask" "B.Paste")
			(net "GND")
		)
		(pad "45" smd rect
			(at 0 37.399976 270)
			(size 1.8034 0.508)
			(layers "B.Cu" "B.Mask" "B.Paste")
			(net "M_M_DQ<26>")
		)
		(pad "46" smd rect
			(at 0 38.250114 270)
			(size 1.8034 0.508)
			(layers "B.Cu" "B.Mask" "B.Paste")
			(net "GND")
		)
		(pad "47" smd rect
			(at 0 39.099998 270)
			(size 1.8034 0.508)
			(layers "B.Cu" "B.Mask" "B.Paste")
			(net "M_M_ECC<4>")
		)
		(pad "48" smd rect
			(at 0 39.949882 270)
			(size 1.8034 0.508)
			(layers "B.Cu" "B.Mask" "B.Paste")
			(net "GND")
		)
		(pad "49" smd rect
			(at 0 40.80002 270)
			(size 1.8034 0.508)
			(layers "B.Cu" "B.Mask" "B.Paste")
			(net "M_M_ECC<0>")
		)
		(pad "50" smd rect
			(at 0 41.649904 270)
			(size 1.8034 0.508)
			(layers "B.Cu" "B.Mask" "B.Paste")
			(net "GND")
		)
		(pad "51" smd rect
			(at 0 42.500042 270)
			(size 1.8034 0.508)
			(layers "B.Cu" "B.Mask" "B.Paste")
			(net "M_M_DQS_DP<17>")
		)
		(pad "52" smd rect
			(at 0 43.349926 270)
			(size 1.8034 0.508)
			(layers "B.Cu" "B.Mask" "B.Paste")
			(net "M_M_DQS_DN<17>")
		)
		(pad "53" smd rect
			(at 0 44.200064 270)
			(size 1.8034 0.508)
			(layers "B.Cu" "B.Mask" "B.Paste")
			(net "GND")
		)
		(pad "54" smd rect
			(at 0 45.049948 270)
			(size 1.8034 0.508)
			(layers "B.Cu" "B.Mask" "B.Paste")
			(net "M_M_ECC<6>")
		)
		(pad "55" smd rect
			(at 0 45.900086 270)
			(size 1.8034 0.508)
			(layers "B.Cu" "B.Mask" "B.Paste")
			(net "GND")
		)
		(pad "56" smd rect
			(at 0 46.74997 270)
			(size 1.8034 0.508)
			(layers "B.Cu" "B.Mask" "B.Paste")
			(net "M_M_ECC<2>")
		)
		(pad "57" smd rect
			(at 0 47.600108 270)
			(size 1.8034 0.508)
			(layers "B.Cu" "B.Mask" "B.Paste")
			(net "GND")
		)
		(pad "58" smd rect
			(at 0 48.449992 270)
			(size 1.8034 0.508)
			(layers "B.Cu" "B.Mask" "B.Paste")
			(net "M_KLM_RST_N")
		)
		(pad "59" smd rect
			(at 0 49.299876 270)
			(size 1.8034 0.508)
			(layers "B.Cu" "B.Mask" "B.Paste")
			(net "PVDDQ_KLM")
		)
		(pad "60" smd rect
			(at 0 50.150014 270)
			(size 1.8034 0.508)
			(layers "B.Cu" "B.Mask" "B.Paste")
			(net "M_M_CKE<2>")
		)
		(pad "61" smd rect
			(at 0 50.999898 270)
			(size 1.8034 0.508)
			(layers "B.Cu" "B.Mask" "B.Paste")
			(net "PVDDQ_KLM")
		)
		(pad "62" smd rect
			(at 0 51.850036 270)
			(size 1.8034 0.508)
			(layers "B.Cu" "B.Mask" "B.Paste")
			(net "M_M_ACT_N")
		)
		(pad "63" smd rect
			(at 0 52.69992 270)
			(size 1.8034 0.508)
			(layers "B.Cu" "B.Mask" "B.Paste")
			(net "M_M_BG<0>")
		)
		(pad "64" smd rect
			(at 0 53.550058 270)
			(size 1.8034 0.508)
			(layers "B.Cu" "B.Mask" "B.Paste")
			(net "PVDDQ_KLM")
		)
		(pad "65" smd rect
			(at 0 54.399942 270)
			(size 1.8034 0.508)
			(layers "B.Cu" "B.Mask" "B.Paste")
			(net "M_M_MA<12>")
		)
		(pad "66" smd rect
			(at 0 55.25008 270)
			(size 1.8034 0.508)
			(layers "B.Cu" "B.Mask" "B.Paste")
			(net "M_M_MA<9>")
		)
		(pad "67" smd rect
			(at 0 56.099964 270)
			(size 1.8034 0.508)
			(layers "B.Cu" "B.Mask" "B.Paste")
			(net "PVDDQ_KLM")
		)
		(pad "68" smd rect
			(at 0 56.950102 270)
			(size 1.8034 0.508)
			(layers "B.Cu" "B.Mask" "B.Paste")
			(net "M_M_MA<8>")
		)
		(pad "69" smd rect
			(at 0 57.799986 270)
			(size 1.8034 0.508)
			(layers "B.Cu" "B.Mask" "B.Paste")
			(net "M_M_MA<6>")
		)
		(pad "70" smd rect
			(at 0 58.650124 270)
			(size 1.8034 0.508)
			(layers "B.Cu" "B.Mask" "B.Paste")
			(net "PVDDQ_KLM")
		)
		(pad "71" smd rect
			(at 0 59.500008 270)
			(size 1.8034 0.508)
			(layers "B.Cu" "B.Mask" "B.Paste")
			(net "M_M_MA<3>")
		)
		(pad "72" smd rect
			(at 0 60.349892 270)
			(size 1.8034 0.508)
			(layers "B.Cu" "B.Mask" "B.Paste")
			(net "M_M_MA<1>")
		)
		(pad "73" smd rect
			(at 0 61.20003 270)
			(size 1.8034 0.508)
			(layers "B.Cu" "B.Mask" "B.Paste")
			(net "PVDDQ_KLM")
		)
		(pad "74" smd rect
			(at 0 62.049914 270)
			(size 1.8034 0.508)
			(layers "B.Cu" "B.Mask" "B.Paste")
			(net "M_M_CLK_DP<2>")
		)
		(pad "75" smd rect
			(at 0 62.900052 270)
			(size 1.8034 0.508)
			(layers "B.Cu" "B.Mask" "B.Paste")
			(net "M_M_CLK_DN<2>")
		)
		(pad "76" smd rect
			(at 0 63.749936 270)
			(size 1.8034 0.508)
			(layers "B.Cu" "B.Mask" "B.Paste")
			(net "PVDDQ_KLM")
		)
		(pad "77" smd rect
			(at 0 64.600074 270)
			(size 1.8034 0.508)
			(layers "B.Cu" "B.Mask" "B.Paste")
			(net "PVTT_KLM")
		)
		(pad "78" smd rect
			(at 0 70.550024 270)
			(size 1.8034 0.508)
			(layers "B.Cu" "B.Mask" "B.Paste")
			(net "FM_DIMM_EVENT_COD_N")
		)
		(pad "79" smd rect
			(at 0 71.399908 270)
			(size 1.8034 0.508)
			(layers "B.Cu" "B.Mask" "B.Paste")
			(net "M_M_MA<0>")
		)
		(pad "80" smd rect
			(at 0 72.250046 270)
			(size 1.8034 0.508)
			(layers "B.Cu" "B.Mask" "B.Paste")
			(net "PVDDQ_KLM")
		)
		(pad "81" smd rect
			(at 0 73.09993 270)
			(size 1.8034 0.508)
			(layers "B.Cu" "B.Mask" "B.Paste")
			(net "M_M_BA<0>")
		)
		(pad "82" smd rect
			(at 0 73.950068 270)
			(size 1.8034 0.508)
			(layers "B.Cu" "B.Mask" "B.Paste")
			(net "M_M_MA<16>")
		)
		(pad "83" smd rect
			(at 0 74.799952 270)
			(size 1.8034 0.508)
			(layers "B.Cu" "B.Mask" "B.Paste")
			(net "PVDDQ_KLM")
		)
		(pad "84" smd rect
			(at 0 75.65009 270)
			(size 1.8034 0.508)
			(layers "B.Cu" "B.Mask" "B.Paste")
			(net "M_M_CS_N<4>")
		)
		(pad "85" smd rect
			(at 0 76.499974 270)
			(size 1.8034 0.508)
			(layers "B.Cu" "B.Mask" "B.Paste")
			(net "PVDDQ_KLM")
		)
		(pad "86" smd rect
			(at 0 77.350112 270)
			(size 1.8034 0.508)
			(layers "B.Cu" "B.Mask" "B.Paste")
			(net "M_M_MA<15>")
		)
		(pad "87" smd rect
			(at 0 78.199996 270)
			(size 1.8034 0.508)
			(layers "B.Cu" "B.Mask" "B.Paste")
			(net "M_M_ODT<2>")
		)
		(pad "88" smd rect
			(at 0 79.04988 270)
			(size 1.8034 0.508)
			(layers "B.Cu" "B.Mask" "B.Paste")
			(net "PVDDQ_KLM")
		)
		(pad "89" smd rect
			(at 0 79.900018 270)
			(size 1.8034 0.508)
			(layers "B.Cu" "B.Mask" "B.Paste")
			(net "M_M_CS_N<5>")
		)
		(pad "90" smd rect
			(at 0 80.749902 270)
			(size 1.8034 0.508)
			(layers "B.Cu" "B.Mask" "B.Paste")
			(net "PVDDQ_KLM")
		)
		(pad "91" smd rect
			(at 0 81.60004 270)
			(size 1.8034 0.508)
			(layers "B.Cu" "B.Mask" "B.Paste")
			(net "M_M_ODT<3>")
		)
		(pad "92" smd rect
			(at 0 82.449924 270)
			(size 1.8034 0.508)
			(layers "B.Cu" "B.Mask" "B.Paste")
			(net "PVDDQ_KLM")
		)
		(pad "93" smd rect
			(at 0 83.300062 270)
			(size 1.8034 0.508)
			(layers "B.Cu" "B.Mask" "B.Paste")
			(net "M_M_CS_N<6>")
		)
		(pad "94" smd rect
			(at 0 84.149946 270)
			(size 1.8034 0.508)
			(layers "B.Cu" "B.Mask" "B.Paste")
			(net "GND")
		)
		(pad "95" smd rect
			(at 0 85.000084 270)
			(size 1.8034 0.508)
			(layers "B.Cu" "B.Mask" "B.Paste")
			(net "M_M_DQ<36>")
		)
		(pad "96" smd rect
			(at 0 85.849968 270)
			(size 1.8034 0.508)
			(layers "B.Cu" "B.Mask" "B.Paste")
			(net "GND")
		)
		(pad "97" smd rect
			(at 0 86.700106 270)
			(size 1.8034 0.508)
			(layers "B.Cu" "B.Mask" "B.Paste")
			(net "M_M_DQ<32>")
		)
		(pad "98" smd rect
			(at 0 87.54999 270)
			(size 1.8034 0.508)
			(layers "B.Cu" "B.Mask" "B.Paste")
			(net "GND")
		)
		(pad "99" smd rect
			(at 0 88.399874 270)
			(size 1.8034 0.508)
			(layers "B.Cu" "B.Mask" "B.Paste")
			(net "M_M_DQS_DP<13>")
		)
		(pad "100" smd rect
			(at 0 89.250012 270)
			(size 1.8034 0.508)
			(layers "B.Cu" "B.Mask" "B.Paste")
			(net "M_M_DQS_DN<13>")
		)
		(pad "101" smd rect
			(at 0 90.099896 270)
			(size 1.8034 0.508)
			(layers "B.Cu" "B.Mask" "B.Paste")
			(net "GND")
		)
		(pad "102" smd rect
			(at 0 90.950034 270)
			(size 1.8034 0.508)
			(layers "B.Cu" "B.Mask" "B.Paste")
			(net "M_M_DQ<38>")
		)
		(pad "103" smd rect
			(at 0 91.799918 270)
			(size 1.8034 0.508)
			(layers "B.Cu" "B.Mask" "B.Paste")
			(net "GND")
		)
		(pad "104" smd rect
			(at 0 92.650056 270)
			(size 1.8034 0.508)
			(layers "B.Cu" "B.Mask" "B.Paste")
			(net "M_M_DQ<34>")
		)
		(pad "105" smd rect
			(at 0 93.49994 270)
			(size 1.8034 0.508)
			(layers "B.Cu" "B.Mask" "B.Paste")
			(net "GND")
		)
		(pad "106" smd rect
			(at 0 94.350078 270)
			(size 1.8034 0.508)
			(layers "B.Cu" "B.Mask" "B.Paste")
			(net "M_M_DQ<44>")
		)
		(pad "107" smd rect
			(at 0 95.199962 270)
			(size 1.8034 0.508)
			(layers "B.Cu" "B.Mask" "B.Paste")
			(net "GND")
		)
		(pad "108" smd rect
			(at 0 96.0501 270)
			(size 1.8034 0.508)
			(layers "B.Cu" "B.Mask" "B.Paste")
			(net "M_M_DQ<40>")
		)
		(pad "109" smd rect
			(at 0 96.899984 270)
			(size 1.8034 0.508)
			(layers "B.Cu" "B.Mask" "B.Paste")
			(net "GND")
		)
		(pad "110" smd rect
			(at 0 97.750122 270)
			(size 1.8034 0.508)
			(layers "B.Cu" "B.Mask" "B.Paste")
			(net "M_M_DQS_DP<14>")
		)
		(pad "111" smd rect
			(at 0 98.600006 270)
			(size 1.8034 0.508)
			(layers "B.Cu" "B.Mask" "B.Paste")
			(net "M_M_DQS_DN<14>")
		)
		(pad "112" smd rect
			(at 0 99.44989 270)
			(size 1.8034 0.508)
			(layers "B.Cu" "B.Mask" "B.Paste")
			(net "GND")
		)
		(pad "113" smd rect
			(at 0 100.300028 270)
			(size 1.8034 0.508)
			(layers "B.Cu" "B.Mask" "B.Paste")
			(net "M_M_DQ<46>")
		)
		(pad "114" smd rect
			(at 0 101.149912 270)
			(size 1.8034 0.508)
			(layers "B.Cu" "B.Mask" "B.Paste")
			(net "GND")
		)
		(pad "115" smd rect
			(at 0 102.00005 270)
			(size 1.8034 0.508)
			(layers "B.Cu" "B.Mask" "B.Paste")
			(net "M_M_DQ<42>")
		)
		(pad "116" smd rect
			(at 0 102.849934 270)
			(size 1.8034 0.508)
			(layers "B.Cu" "B.Mask" "B.Paste")
			(net "GND")
		)
		(pad "117" smd rect
			(at 0 103.700072 270)
			(size 1.8034 0.508)
			(layers "B.Cu" "B.Mask" "B.Paste")
			(net "M_M_DQ<52>")
		)
		(pad "118" smd rect
			(at 0 104.549956 270)
			(size 1.8034 0.508)
			(layers "B.Cu" "B.Mask" "B.Paste")
			(net "GND")
		)
		(pad "119" smd rect
			(at 0 105.400094 270)
			(size 1.8034 0.508)
			(layers "B.Cu" "B.Mask" "B.Paste")
			(net "M_M_DQ<48>")
		)
		(pad "120" smd rect
			(at 0 106.249978 270)
			(size 1.8034 0.508)
			(layers "B.Cu" "B.Mask" "B.Paste")
			(net "GND")
		)
	)
)
